# T6G (Grand Teton) — schematic netlist excerpt (pin names and nets, part order shuffled) for the footprints in the layout excerpt that follows; sources: Cadence DE-HDL packaged netlist, KiCad conversion of 04192023_DAF0TMB3IC0_F0TG_MB_C_brd_V02_OCP.brd

R2847  Q_RES  33.2 1% CHIP  pkg 0402LF  page 81 : A = RST_BMC_FROM_SWB_ISO_R_N ; B = RST_BMC_FROM_SWB_ISO_N
R418  Q_RES  2.2K 5% CHIP  pkg 0402LF  page 27 : A = APML_CPU0_ALERT_N ; B = PVDD18_S5_P0

(kicad_pcb
	(version 20260206)
	(generator "pcbnew")
	(generator_version "10.0")
	(general
		(thickness 1.6)
		(legacy_teardrops no)
	)
	(paper "A4")
	(title_block
		(title "04192023_DAF0TMB3IC0_F0TG_MB_C_brd_V02_OCP.brd")
		(comment 1 "Grand Teton / footprints 4354-4355 of 8354")
	)
	(layers
		(0 "F.Cu" signal "TOP")
		(4 "In1.Cu" signal "GND")
		(6 "In2.Cu" signal "IN1")
		(8 "In3.Cu" signal "GND1")
		(10 "In4.Cu" signal "IN2")
		(12 "In5.Cu" signal "GND2")
		(14 "In6.Cu" signal "IN3")
		(16 "In7.Cu" signal "GND3")
		(18 "In8.Cu" signal "VCC")
		(20 "In9.Cu" signal "VCC1")
		(22 "In10.Cu" signal "GND4")
		(24 "In11.Cu" signal "IN4")
		(26 "In12.Cu" signal "GND5")
		(28 "In13.Cu" signal "IN5")
		(30 "In14.Cu" signal "GND6")
		(32 "In15.Cu" signal "IN6")
		(34 "In16.Cu" signal "GND7")
		(2 "B.Cu" signal "BOTTOM")
		(9 "F.Adhes" user "F.Adhesive")
		(11 "B.Adhes" user "B.Adhesive")
		(13 "F.Paste" user "Package Geometry/Pastemask Top")
		(15 "B.Paste" user "Package Geometry/Pastemask Bottom")
		(5 "F.SilkS" user "Ref Des/Silkscreen Top")
		(7 "B.SilkS" user "Ref Des/Silkscreen Bottom")
		(1 "F.Mask" user "Board Geometry/Soldermask Top")
		(3 "B.Mask" user "Board Geometry/Soldermask Bottom")
		(17 "Dwgs.User" user "User.Drawings")
		(19 "Cmts.User" user "User.Comments")
		(21 "Eco1.User" user "User.Eco1")
		(23 "Eco2.User" user "User.Eco2")
		(25 "Edge.Cuts" user "Board Geometry/Outline")
		(27 "Margin" user)
		(31 "F.CrtYd" user "Package Geometry/Place Bound Top")
		(29 "B.CrtYd" user "Package Geometry/Place Bound Bottom")
		(35 "F.Fab" user "Ref Des/Assembly Top")
		(33 "B.Fab" user "Ref Des/Assembly Bottom")
	)
	(footprint ""
		(layer "F.Cu")
		(at 324.529958 -193.925952 -90)
		(property "Reference" "R418"
			(at 0 0 270)
			(layer "F.SilkS")
			(hide yes)
			(effects
				(font
					(size 1.27 1.27)
				)
			)
		)
		(property "Value" ""
			(at 0 0 270)
			(layer "F.Fab")
			(effects
				(font
					(size 1.27 1.27)
				)
			)
		)
		(duplicate_pad_numbers_are_jumpers no)
		(fp_line
			(start -0.7874 0.4064)
			(end -0.7874 -0.4064)
			(stroke
				(width 0.1524)
				(type default)
			)
			(layer "F.SilkS")
		)
		(fp_line
			(start 0.7874 0.4064)
			(end -0.7874 0.4064)
			(stroke
				(width 0.1524)
				(type default)
			)
			(layer "F.SilkS")
		)
		(fp_line
			(start -0.7874 -0.4064)
			(end 0.7874 -0.4064)
			(stroke
				(width 0.1524)
				(type default)
			)
			(layer "F.SilkS")
		)
		(fp_line
			(start 0.7874 -0.4064)
			(end 0.7874 0.4064)
			(stroke
				(width 0.1524)
				(type default)
			)
			(layer "F.SilkS")
		)
		(fp_line
			(start -0.67945 0.3048)
			(end -0.67945 -0.305054)
			(stroke
				(width 0.1)
				(type default)
			)
			(layer "F.Fab")
		)
		(fp_line
			(start -0.12065 0.3048)
			(end -0.67945 0.3048)
			(stroke
				(width 0.1)
				(type default)
			)
			(layer "F.Fab")
		)
		(fp_line
			(start 0.120396 0.3048)
			(end 0.120396 0.2794)
			(stroke
				(width 0.1)
				(type default)
			)
			(layer "F.Fab")
		)
		(fp_line
			(start 0.67945 0.3048)
			(end 0.120396 0.3048)
			(stroke
				(width 0.1)
				(type default)
			)
			(layer "F.Fab")
		)
		(fp_line
			(start -0.12065 0.2794)
			(end -0.12065 0.3048)
			(stroke
				(width 0.1)
				(type default)
			)
			(layer "F.Fab")
		)
		(fp_line
			(start 0.120396 0.2794)
			(end -0.12065 0.2794)
			(stroke
				(width 0.1)
				(type default)
			)
			(layer "F.Fab")
		)
		(fp_line
			(start -0.12065 -0.2794)
			(end 0.12065 -0.2794)
			(stroke
				(width 0.1)
				(type default)
			)
			(layer "F.Fab")
		)
		(fp_line
			(start 0.12065 -0.2794)
			(end 0.12065 -0.3048)
			(stroke
				(width 0.1)
				(type default)
			)
			(layer "F.Fab")
		)
		(fp_line
			(start 0.12065 -0.3048)
			(end 0.67945 -0.3048)
			(stroke
				(width 0.1)
				(type default)
			)
			(layer "F.Fab")
		)
		(fp_line
			(start 0.67945 -0.3048)
			(end 0.67945 0.3048)
			(stroke
				(width 0.1)
				(type default)
			)
			(layer "F.Fab")
		)
		(fp_line
			(start -0.67945 -0.305054)
			(end -0.12065 -0.305054)
			(stroke
				(width 0.1)
				(type default)
			)
			(layer "F.Fab")
		)
		(fp_line
			(start -0.12065 -0.305054)
			(end -0.12065 -0.2794)
			(stroke
				(width 0.1)
				(type default)
			)
			(layer "F.Fab")
		)
		(pad "1" smd circle
			(at -0.40005 0 270)
			(size 0 0)
			(layers "F.Cu" "F.Mask" "F.Paste")
			(net "APML_CPU0_ALERT_N")
		)
		(pad "2" smd circle
			(at 0.40005 0 270)
			(size 0 0)
			(layers "F.Cu" "F.Mask" "F.Paste")
			(net "PVDD18_S5_P0")
		)
	)
	(footprint ""
		(layer "F.Cu")
		(at 197.269608 -126.833376)
		(property "Reference" "R2847"
			(at 0 0 0)
			(layer "F.SilkS")
			(hide yes)
			(effects
				(font
					(size 1.27 1.27)
				)
			)
		)
		(property "Value" ""
			(at 0 0 0)
			(layer "F.Fab")
			(effects
				(font
					(size 1.27 1.27)
				)
			)
		)
		(duplicate_pad_numbers_are_jumpers no)
		(fp_line
			(start -0.7874 -0.4064)
			(end 0.7874 -0.4064)
			(stroke
				(width 0.1524)
				(type default)
			)
			(layer "F.SilkS")
		)
		(fp_line
			(start -0.7874 0.4064)
			(end -0.7874 -0.4064)
			(stroke
				(width 0.1524)
				(type default)
			)
			(layer "F.SilkS")
		)
		(fp_line
			(start 0.7874 -0.4064)
			(end 0.7874 0.4064)
			(stroke
				(width 0.1524)
				(type default)
			)
			(layer "F.SilkS")
		)
		(fp_line
			(start 0.7874 0.4064)
			(end -0.7874 0.4064)
			(stroke
				(width 0.1524)
				(type default)
			)
			(layer "F.SilkS")
		)
		(fp_line
			(start -0.67945 -0.305054)
			(end -0.12065 -0.305054)
			(stroke
				(width 0.1)
				(type default)
			)
			(layer "F.Fab")
		)
		(fp_line
			(start -0.67945 0.3048)
			(end -0.67945 -0.305054)
			(stroke
				(width 0.1)
				(type default)
			)
			(layer "F.Fab")
		)
		(fp_line
			(start -0.12065 -0.305054)
			(end -0.12065 -0.2794)
			(stroke
				(width 0.1)
				(type default)
			)
			(layer "F.Fab")
		)
		(fp_line
			(start -0.12065 -0.2794)
			(end 0.12065 -0.2794)
			(stroke
				(width 0.1)
				(type default)
			)
			(layer "F.Fab")
		)
		(fp_line
			(start -0.12065 0.2794)
			(end -0.12065 0.3048)
			(stroke
				(width 0.1)
				(type default)
			)
			(layer "F.Fab")
		)
		(fp_line
			(start -0.12065 0.3048)
			(end -0.67945 0.3048)
			(stroke
				(width 0.1)
				(type default)
			)
			(layer "F.Fab")
		)
		(fp_line
			(start 0.120396 0.2794)
			(end -0.12065 0.2794)
			(stroke
				(width 0.1)
				(type default)
			)
			(layer "F.Fab")
		)
		(fp_line
			(start 0.120396 0.3048)
			(end 0.120396 0.2794)
			(stroke
				(width 0.1)
				(type default)
			)
			(layer "F.Fab")
		)
		(fp_line
			(start 0.12065 -0.3048)
			(end 0.67945 -0.3048)
			(stroke
				(width 0.1)
				(type default)
			)
			(layer "F.Fab")
		)
		(fp_line
			(start 0.12065 -0.2794)
			(end 0.12065 -0.3048)
			(stroke
				(width 0.1)
				(type default)
			)
			(layer "F.Fab")
		)
		(fp_line
			(start 0.67945 -0.3048)
			(end 0.67945 0.3048)
			(stroke
				(width 0.1)
				(type default)
			)
			(layer "F.Fab")
		)
		(fp_line
			(start 0.67945 0.3048)
			(end 0.120396 0.3048)
			(stroke
				(width 0.1)
				(type default)
			)
			(layer "F.Fab")
		)
		(pad "1" smd circle
			(at -0.40005 0)
			(size 0 0)
			(layers "F.Cu" "F.Mask" "F.Paste")
			(net "RST_BMC_FROM_SWB_ISO_R_N")
		)
		(pad "2" smd circle
			(at 0.40005 0)
			(size 0 0)
			(layers "F.Cu" "F.Mask" "F.Paste")
			(net "RST_BMC_FROM_SWB_ISO_N")
		)
	)
)
